# SCM (Grand Teton) — schematic netlist excerpt (pin names and nets, part order shuffled) for the footprints in the layout excerpt that follows; sources: Cadence DE-HDL packaged netlist, KiCad conversion of 12092022_DA0F0TMDCD0_F0T_Management_Board_D_brd_V3_OCP.brd

J16  PICOPROBE_BXA  DELTA-L 4.0 EMPTY  pkg TRIANG_LAUNCH_3PXB  page 58
  \1_p\  = 85_5INCH_IN4_DN
  \2_n\  = 85_5INCH_IN4_DP
  \3_g\  = GND_P1

(kicad_pcb
	(version 20260206)
	(generator "pcbnew")
	(generator_version "10.0")
	(general
		(thickness 1.6)
		(legacy_teardrops no)
	)
	(paper "A4")
	(title_block
		(title "12092022_DA0F0TMDCD0_F0T_Management_Board_D_brd_V3_OCP.brd")
		(comment 1 "Grand Teton / footprints 265-265 of 1440")
	)
	(layers
		(0 "F.Cu" signal "TOP")
		(4 "In1.Cu" signal "GND")
		(6 "In2.Cu" signal "IN1")
		(8 "In3.Cu" signal "GND1")
		(10 "In4.Cu" signal "IN2")
		(12 "In5.Cu" signal "VCC")
		(14 "In6.Cu" signal "VCC1")
		(16 "In7.Cu" signal "IN3")
		(18 "In8.Cu" signal "GND2")
		(20 "In9.Cu" signal "IN4")
		(22 "In10.Cu" signal "GND3")
		(2 "B.Cu" signal "BOTTOM")
		(9 "F.Adhes" user "F.Adhesive")
		(11 "B.Adhes" user "B.Adhesive")
		(13 "F.Paste" user "Package Geometry/Pastemask Top")
		(15 "B.Paste" user "Package Geometry/Pastemask Bottom")
		(5 "F.SilkS" user "Ref Des/Silkscreen Top")
		(7 "B.SilkS" user "Ref Des/Silkscreen Bottom")
		(1 "F.Mask" user "Board Geometry/Soldermask Top")
		(3 "B.Mask" user "Board Geometry/Soldermask Bottom")
		(17 "Dwgs.User" user "User.Drawings")
		(19 "Cmts.User" user "User.Comments")
		(21 "Eco1.User" user "User.Eco1")
		(23 "Eco2.User" user "User.Eco2")
		(25 "Edge.Cuts" user "Board Geometry/Outline")
		(27 "Margin" user)
		(31 "F.CrtYd" user "Package Geometry/Place Bound Top")
		(29 "B.CrtYd" user "Package Geometry/Place Bound Bottom")
		(35 "F.Fab" user "Ref Des/Assembly Top")
		(33 "B.Fab" user "Ref Des/Assembly Bottom")
	)
	(footprint ""
		(layer "F.Cu")
		(at 95.904304 42.085514 90)
		(property "Reference" "J16"
			(at -1.094486 2.801366 90)
			(unlocked yes)
			(layer "F.SilkS")
			(effects
				(font
					(size 0.7874 0.5842)
					(thickness 0.1524)
				)
				(justify left)
			)
		)
		(property "Value" ""
			(at 0 0 90)
			(layer "F.Fab")
			(effects
				(font
					(size 1.27 1.27)
				)
			)
		)
		(duplicate_pad_numbers_are_jumpers no)
		(fp_line
			(start 1.2192 -2.1082)
			(end 1.2192 -0.801878)
			(stroke
				(width 0.1524)
				(type default)
			)
			(layer "F.SilkS")
		)
		(fp_line
			(start -1.2192 -2.1082)
			(end 1.2192 -2.1082)
			(stroke
				(width 0.1524)
				(type default)
			)
			(layer "F.SilkS")
		)
		(fp_line
			(start 1.2192 0.810768)
			(end 1.2192 2.1082)
			(stroke
				(width 0.1524)
				(type default)
			)
			(layer "F.SilkS")
		)
		(fp_line
			(start 1.2192 2.1082)
			(end -1.2192 2.1082)
			(stroke
				(width 0.1524)
				(type default)
			)
			(layer "F.SilkS")
		)
		(fp_line
			(start -1.2192 2.1082)
			(end -1.2192 -2.1082)
			(stroke
				(width 0.1524)
				(type default)
			)
			(layer "F.SilkS")
		)
		(pad "" np_thru_hole circle
			(at -2.8829 -1.27)
			(size 1.0414 1.0414)
			(drill 1.0414)
			(layers "*.Cu" "*.Mask")
			(clearance 0.381)
			(thermal_gap 0.381)
		)
		(pad "" np_thru_hole circle
			(at -2.8829 1.27)
			(size 1.0414 1.0414)
			(drill 1.0414)
			(layers "*.Cu" "*.Mask")
			(clearance 0.381)
			(thermal_gap 0.381)
		)
		(pad "" np_thru_hole circle
			(at 3.4671 -1.27)
			(size 1.0414 1.0414)
			(drill 1.0414)
			(layers "*.Cu" "*.Mask")
			(clearance 0.381)
			(thermal_gap 0.381)
		)
		(pad "" np_thru_hole circle
			(at 3.4671 1.27)
			(size 1.0414 1.0414)
			(drill 1.0414)
			(layers "*.Cu" "*.Mask")
			(clearance 0.381)
			(thermal_gap 0.381)
		)
		(pad "1" smd rect
			(at 0.8255 -0.249936)
			(size 0.3048 0.508)
			(layers "F.Cu" "F.Mask" "F.Paste")
			(net "85_5INCH_IN4_DN")
		)
		(pad "2" smd rect
			(at 0.8255 0.249936)
			(size 0.3048 0.508)
			(layers "F.Cu" "F.Mask" "F.Paste")
			(net "85_5INCH_IN4_DP")
		)
		(pad "3" smd circle
			(at 0 0 90)
			(size 0 0)
			(layers "F.Cu" "F.Mask" "F.Paste")
			(net "GND_P1")
		)
		(zone
			(layer "F.Cu")
			(hatch none 0.5)
			(connect_pads
				(clearance 0)
			)
			(min_thickness 0.25)
			(keepout
				(tracks not_allowed)
				(vias allowed)
				(pads allowed)
				(copperpour not_allowed)
				(footprints allowed)
			)
			(placement
				(enabled no)
				(sheetname "")
			)
			(fill
				(thermal_gap 0.5)
				(thermal_bridge_width 0.5)
				(island_removal_mode 0)
			)
			(polygon
				(pts
					(xy 95.355664 40.967914) (xy 95.451168 40.967914) (xy 95.451168 41.564814) (xy 95.857568 41.564814)
					(xy 95.857568 40.967914) (xy 95.95104 40.967914) (xy 95.95104 41.564814) (xy 96.35744 41.564814)
					(xy 96.35744 40.967914) (xy 96.452944 40.967914) (xy 96.452944 41.666414) (xy 95.355664 41.666414)
				)
			)
		)
		(zone
			(layers "F.Cu" "B.Cu" "In1.Cu" "In2.Cu" "In3.Cu" "In4.Cu" "In5.Cu" "In6.Cu"
				"In7.Cu" "In8.Cu" "In9.Cu" "In10.Cu"
			)
			(hatch none 0.5)
			(connect_pads
				(clearance 0)
			)
			(min_thickness 0.25)
			(keepout
				(tracks not_allowed)
				(vias allowed)
				(pads allowed)
				(copperpour not_allowed)
				(footprints allowed)
			)
			(placement
				(enabled no)
				(sheetname "")
			)
			(fill
				(thermal_gap 0.5)
				(thermal_bridge_width 0.5)
				(island_removal_mode 0)
			)
			(polygon
				(pts
					(arc
						(start 95.561404 38.618414)
						(mid 93.707204 38.618414)
						(end 95.561404 38.618414)
					)
				)
			)
		)
		(zone
			(layers "F.Cu" "B.Cu" "In1.Cu" "In2.Cu" "In3.Cu" "In4.Cu" "In5.Cu" "In6.Cu"
				"In7.Cu" "In8.Cu" "In9.Cu" "In10.Cu"
			)
			(hatch none 0.5)
			(connect_pads
				(clearance 0)
			)
			(min_thickness 0.25)
			(keepout
				(tracks not_allowed)
				(vias allowed)
				(pads allowed)
				(copperpour not_allowed)
				(footprints allowed)
			)
			(placement
				(enabled no)
				(sheetname "")
			)
			(fill
				(thermal_gap 0.5)
				(thermal_bridge_width 0.5)
				(island_removal_mode 0)
			)
			(polygon
				(pts
					(arc
						(start 95.561404 44.968414)
						(mid 93.707204 44.968414)
						(end 95.561404 44.968414)
					)
				)
			)
		)
		(zone
			(layers "F.Cu" "B.Cu" "In1.Cu" "In2.Cu" "In3.Cu" "In4.Cu" "In5.Cu" "In6.Cu"
				"In7.Cu" "In8.Cu" "In9.Cu" "In10.Cu"
			)
			(hatch none 0.5)
			(connect_pads
				(clearance 0)
			)
			(min_thickness 0.25)
			(keepout
				(tracks not_allowed)
				(vias allowed)
				(pads allowed)
				(copperpour not_allowed)
				(footprints allowed)
			)
			(placement
				(enabled no)
				(sheetname "")
			)
			(fill
				(thermal_gap 0.5)
				(thermal_bridge_width 0.5)
				(island_removal_mode 0)
			)
			(polygon
				(pts
					(arc
						(start 98.101404 38.618414)
						(mid 96.247204 38.618414)
						(end 98.101404 38.618414)
					)
				)
			)
		)
		(zone
			(layers "F.Cu" "B.Cu" "In1.Cu" "In2.Cu" "In3.Cu" "In4.Cu" "In5.Cu" "In6.Cu"
				"In7.Cu" "In8.Cu" "In9.Cu" "In10.Cu"
			)
			(hatch none 0.5)
			(connect_pads
				(clearance 0)
			)
			(min_thickness 0.25)
			(keepout
				(tracks not_allowed)
				(vias allowed)
				(pads allowed)
				(copperpour not_allowed)
				(footprints allowed)
			)
			(placement
				(enabled no)
				(sheetname "")
			)
			(fill
				(thermal_gap 0.5)
				(thermal_bridge_width 0.5)
				(island_removal_mode 0)
			)
			(polygon
				(pts
					(arc
						(start 98.101404 44.968414)
						(mid 96.247204 44.968414)
						(end 98.101404 44.968414)
					)
				)
			)
		)
	)
)
